(kicad_pcb
	(version 20260206)
	(generator "pcbnew")
	(generator_version "10.0")
	(general
		(thickness 1.6)
		(legacy_teardrops no)
	)
	(paper "A4")
	(title_block
		(title "peb — Lightning_PEB_BRD.brd")
		(comment 1 "Lightning (Wiwynn / Facebook NVMe JBOF) / footprints 1052-1059 of 2563")
	)
	(layers
		(0 "F.Cu" signal "TOP")
		(4 "In1.Cu" signal "L2GND")
		(6 "In2.Cu" signal "L3")
		(8 "In3.Cu" signal "L4VCC")
		(10 "In4.Cu" signal "L5VCC")
		(12 "In5.Cu" signal "L6")
		(14 "In6.Cu" signal "L7GND")
		(2 "B.Cu" signal "BOTTOM")
		(9 "F.Adhes" user "F.Adhesive")
		(11 "B.Adhes" user "B.Adhesive")
		(13 "F.Paste" user "Package Geometry/Pastemask Top")
		(15 "B.Paste" user "Package Geometry/Pastemask Bottom")
		(5 "F.SilkS" user "Ref Des/Silkscreen Top")
		(7 "B.SilkS" user "Ref Des/Silkscreen Bottom")
		(1 "F.Mask" user "Board Geometry/Soldermask Top")
		(3 "B.Mask" user "Board Geometry/Soldermask Bottom")
		(17 "Dwgs.User" user "User.Drawings")
		(19 "Cmts.User" user "User.Comments")
		(21 "Eco1.User" user "User.Eco1")
		(23 "Eco2.User" user "User.Eco2")
		(25 "Edge.Cuts" user "Board Geometry/Outline")
		(27 "Margin" user)
		(31 "F.CrtYd" user "Package Geometry/Place Bound Top")
		(29 "B.CrtYd" user "Package Geometry/Place Bound Bottom")
		(35 "F.Fab" user "Ref Des/Assembly Top")
		(33 "B.Fab" user "Ref Des/Assembly Bottom")
	)
	(footprint ""
		(layer "F.Cu")
		(at 335.026 -73.66 -90)
		(property "Reference" "C270"
			(at 0 0 270)
			(layer "F.SilkS")
			(hide yes)
			(effects
				(font
					(size 1.27 1.27)
				)
			)
		)
		(property "Value" "SC100P50V2JN-3GP"
			(at 1.1811 -2.7051 270)
			(unlocked yes)
			(layer "F.Fab")
			(hide yes)
			(effects
				(font
					(size 1.016 1.016)
					(thickness 0.1524)
				)
			)
		)
		(property "Device Type" "C402H22"
			(at 1.1811 -4.2291 270)
			(unlocked yes)
			(layer "F.Fab")
			(hide yes)
			(effects
				(font
					(size 1.016 1.016)
					(thickness 0.1524)
				)
			)
		)
		(duplicate_pad_numbers_are_jumpers no)
		(fp_rect
			(start -0.4318 0.9525)
			(end 0.4318 -0.9525)
			(stroke
				(width 0)
				(type default)
			)
			(fill no)
			(layer "F.CrtYd")
		)
		(fp_rect
			(start -0.4318 0.9525)
			(end 0.4318 -0.9525)
			(stroke
				(width 0)
				(type default)
			)
			(fill no)
			(layer "F.Fab")
		)
		(pad "1" smd custom
			(at 0 -0.4445 270)
			(size 0.1524 0.1524)
			(layers "F.Cu" "F.Mask" "F.Paste")
			(net "P0V9_E_VFB")
			(options
				(clearance outline)
				(anchor circle)
			)
			(primitives
				(gr_poly
					(pts
						(arc
							(start 0.3048 -0.2032)
							(mid 0.275042 -0.275042)
							(end 0.2032 -0.3048)
						)
						(arc
							(start -0.2032 -0.3048)
							(mid -0.275042 -0.275042)
							(end -0.3048 -0.2032)
						)
						(arc
							(start -0.3048 0.2032)
							(mid -0.275042 0.275042)
							(end -0.2032 0.3048)
						)
						(arc
							(start 0.2032 0.3048)
							(mid 0.275042 0.275042)
							(end 0.3048 0.2032)
						)
					)
					(width 0)
					(fill yes)
				)
			)
		)
		(pad "2" smd custom
			(at 0 0.4445 270)
			(size 0.1524 0.1524)
			(layers "F.Cu" "F.Mask" "F.Paste")
			(net "P0V9_E_VFB_R")
			(options
				(clearance outline)
				(anchor circle)
			)
			(primitives
				(gr_poly
					(pts
						(arc
							(start 0.3048 -0.2032)
							(mid 0.275042 -0.275042)
							(end 0.2032 -0.3048)
						)
						(arc
							(start -0.2032 -0.3048)
							(mid -0.275042 -0.275042)
							(end -0.3048 -0.2032)
						)
						(arc
							(start -0.3048 0.2032)
							(mid -0.275042 0.275042)
							(end -0.2032 0.3048)
						)
						(arc
							(start 0.2032 0.3048)
							(mid 0.275042 0.275042)
							(end 0.3048 0.2032)
						)
					)
					(width 0)
					(fill yes)
				)
			)
		)
	)
	(footprint ""
		(layer "F.Cu")
		(at 84.190332 -74.230992 -90)
		(property "Reference" "C274"
			(at 0 0 270)
			(layer "F.SilkS")
			(hide yes)
			(effects
				(font
					(size 1.27 1.27)
				)
			)
		)
		(property "Value" "SCD1U16V2KX-3GP"
			(at 1.1811 -2.7051 270)
			(unlocked yes)
			(layer "F.Fab")
			(hide yes)
			(effects
				(font
					(size 1.016 1.016)
					(thickness 0.1524)
				)
			)
		)
		(property "Device Type" "C402H22"
			(at 1.1811 -4.2291 270)
			(unlocked yes)
			(layer "F.Fab")
			(hide yes)
			(effects
				(font
					(size 1.016 1.016)
					(thickness 0.1524)
				)
			)
		)
		(duplicate_pad_numbers_are_jumpers no)
		(fp_rect
			(start -0.4318 0.9525)
			(end 0.4318 -0.9525)
			(stroke
				(width 0)
				(type default)
			)
			(fill no)
			(layer "F.CrtYd")
		)
		(fp_rect
			(start -0.4318 0.9525)
			(end 0.4318 -0.9525)
			(stroke
				(width 0)
				(type default)
			)
			(fill no)
			(layer "F.Fab")
		)
		(pad "1" smd custom
			(at 0 -0.4445 270)
			(size 0.1524 0.1524)
			(layers "F.Cu" "F.Mask" "F.Paste")
			(net "P3V3_STBY")
			(options
				(clearance outline)
				(anchor circle)
			)
			(primitives
				(gr_poly
					(pts
						(arc
							(start 0.3048 -0.2032)
							(mid 0.275042 -0.275042)
							(end 0.2032 -0.3048)
						)
						(arc
							(start -0.2032 -0.3048)
							(mid -0.275042 -0.275042)
							(end -0.3048 -0.2032)
						)
						(arc
							(start -0.3048 0.2032)
							(mid -0.275042 0.275042)
							(end -0.2032 0.3048)
						)
						(arc
							(start 0.2032 0.3048)
							(mid 0.275042 0.275042)
							(end 0.3048 0.2032)
						)
					)
					(width 0)
					(fill yes)
				)
			)
		)
		(pad "2" smd custom
			(at 0 0.4445 270)
			(size 0.1524 0.1524)
			(layers "F.Cu" "F.Mask" "F.Paste")
			(net "GND")
			(options
				(clearance outline)
				(anchor circle)
			)
			(primitives
				(gr_poly
					(pts
						(arc
							(start 0.3048 -0.2032)
							(mid 0.275042 -0.275042)
							(end 0.2032 -0.3048)
						)
						(arc
							(start -0.2032 -0.3048)
							(mid -0.275042 -0.275042)
							(end -0.3048 -0.2032)
						)
						(arc
							(start -0.3048 0.2032)
							(mid -0.275042 0.275042)
							(end -0.2032 0.3048)
						)
						(arc
							(start 0.2032 0.3048)
							(mid 0.275042 0.275042)
							(end 0.3048 0.2032)
						)
					)
					(width 0)
					(fill yes)
				)
			)
		)
	)
	(footprint ""
		(layer "F.Cu")
		(at 69.699124 -195.681092)
		(property "Reference" "R7912"
			(at 0 0 0)
			(layer "F.SilkS")
			(hide yes)
			(effects
				(font
					(size 1.27 1.27)
				)
			)
		)
		(property "Value" "0R2J-2-GP"
			(at 0.064008 -3.993896 0)
			(unlocked yes)
			(layer "F.Fab")
			(hide yes)
			(effects
				(font
					(size 1.016 1.016)
					(thickness 0.1524)
				)
			)
		)
		(property "Device Type" "R402H16"
			(at 0.064008 -5.517896 0)
			(unlocked yes)
			(layer "F.Fab")
			(hide yes)
			(effects
				(font
					(size 1.016 1.016)
					(thickness 0.1524)
				)
			)
		)
		(duplicate_pad_numbers_are_jumpers no)
		(fp_line
			(start -0.508 -0.9398)
			(end -0.508 0.9398)
			(stroke
				(width 0.1524)
				(type default)
			)
			(layer "F.SilkS")
		)
		(fp_line
			(start 0.508 -0.9398)
			(end -0.508 -0.9398)
			(stroke
				(width 0.1524)
				(type default)
			)
			(layer "F.SilkS")
		)
		(fp_rect
			(start -0.508 0.9398)
			(end 0.508 -0.9398)
			(stroke
				(width 0)
				(type default)
			)
			(fill no)
			(layer "F.CrtYd")
		)
		(fp_rect
			(start -0.508 0.9398)
			(end 0.508 -0.9398)
			(stroke
				(width 0)
				(type default)
			)
			(fill no)
			(layer "F.Fab")
		)
		(pad "1" smd custom
			(at 0 -0.4445)
			(size 0.1397 0.1397)
			(layers "F.Cu" "F.Mask" "F.Paste")
			(net "TWI_SDA1")
			(options
				(clearance outline)
				(anchor circle)
			)
			(primitives
				(gr_poly
					(pts
						(arc
							(start -0.1778 -0.2794)
							(mid -0.249642 -0.249642)
							(end -0.2794 -0.1778)
						)
						(arc
							(start -0.2794 0.1778)
							(mid -0.249642 0.249642)
							(end -0.1778 0.2794)
						)
						(arc
							(start 0.1778 0.2794)
							(mid 0.249642 0.249642)
							(end 0.2794 0.1778)
						)
						(arc
							(start 0.2794 -0.1778)
							(mid 0.249642 -0.249642)
							(end 0.1778 -0.2794)
						)
					)
					(width 0)
					(fill yes)
				)
			)
		)
		(pad "2" smd custom
			(at 0 0.4445)
			(size 0.1397 0.1397)
			(layers "F.Cu" "F.Mask" "F.Paste")
			(net "I2C_GPIO_SDA_1")
			(options
				(clearance outline)
				(anchor circle)
			)
			(primitives
				(gr_poly
					(pts
						(arc
							(start -0.1778 -0.2794)
							(mid -0.249642 -0.249642)
							(end -0.2794 -0.1778)
						)
						(arc
							(start -0.2794 0.1778)
							(mid -0.249642 0.249642)
							(end -0.1778 0.2794)
						)
						(arc
							(start 0.1778 0.2794)
							(mid 0.249642 0.249642)
							(end 0.2794 0.1778)
						)
						(arc
							(start 0.2794 -0.1778)
							(mid 0.249642 -0.249642)
							(end 0.1778 -0.2794)
						)
					)
					(width 0)
					(fill yes)
				)
			)
		)
	)
	(footprint ""
		(layer "F.Cu")
		(at 215.9762 -4.064 180)
		(property "Reference" "R7907"
			(at 0 0 180)
			(layer "F.SilkS")
			(hide yes)
			(effects
				(font
					(size 1.27 1.27)
				)
			)
		)
		(property "Value" "0R2J-2-GP"
			(at 0.064008 -3.993896 180)
			(unlocked yes)
			(layer "F.Fab")
			(hide yes)
			(effects
				(font
					(size 1.016 1.016)
					(thickness 0.1524)
				)
			)
		)
		(property "Device Type" "R402H16"
			(at 0.064008 -5.517896 180)
			(unlocked yes)
			(layer "F.Fab")
			(hide yes)
			(effects
				(font
					(size 1.016 1.016)
					(thickness 0.1524)
				)
			)
		)
		(duplicate_pad_numbers_are_jumpers no)
		(fp_line
			(start 0.508 -0.9398)
			(end -0.508 -0.9398)
			(stroke
				(width 0.1524)
				(type default)
			)
			(layer "F.SilkS")
		)
		(fp_line
			(start -0.508 -0.9398)
			(end -0.508 0.9398)
			(stroke
				(width 0.1524)
				(type default)
			)
			(layer "F.SilkS")
		)
		(fp_rect
			(start -0.508 0.9398)
			(end 0.508 -0.9398)
			(stroke
				(width 0)
				(type default)
			)
			(fill no)
			(layer "F.CrtYd")
		)
		(fp_rect
			(start -0.508 0.9398)
			(end 0.508 -0.9398)
			(stroke
				(width 0)
				(type default)
			)
			(fill no)
			(layer "F.Fab")
		)
		(pad "1" smd custom
			(at 0 -0.4445 180)
			(size 0.1397 0.1397)
			(layers "F.Cu" "F.Mask" "F.Paste")
			(net "HOST1_RST_N_R")
			(options
				(clearance outline)
				(anchor circle)
			)
			(primitives
				(gr_poly
					(pts
						(arc
							(start -0.1778 -0.2794)
							(mid -0.249642 -0.249642)
							(end -0.2794 -0.1778)
						)
						(arc
							(start -0.2794 0.1778)
							(mid -0.249642 0.249642)
							(end -0.1778 0.2794)
						)
						(arc
							(start 0.1778 0.2794)
							(mid 0.249642 0.249642)
							(end 0.2794 0.1778)
						)
						(arc
							(start 0.2794 -0.1778)
							(mid 0.249642 -0.249642)
							(end 0.1778 -0.2794)
						)
					)
					(width 0)
					(fill yes)
				)
			)
		)
		(pad "2" smd custom
			(at 0 0.4445 180)
			(size 0.1397 0.1397)
			(layers "F.Cu" "F.Mask" "F.Paste")
			(net "HOST1_RST_N")
			(options
				(clearance outline)
				(anchor circle)
			)
			(primitives
				(gr_poly
					(pts
						(arc
							(start -0.1778 -0.2794)
							(mid -0.249642 -0.249642)
							(end -0.2794 -0.1778)
						)
						(arc
							(start -0.2794 0.1778)
							(mid -0.249642 0.249642)
							(end -0.1778 0.2794)
						)
						(arc
							(start 0.1778 0.2794)
							(mid 0.249642 0.249642)
							(end 0.2794 0.1778)
						)
						(arc
							(start 0.2794 -0.1778)
							(mid 0.249642 -0.249642)
							(end 0.1778 -0.2794)
						)
					)
					(width 0)
					(fill yes)
				)
			)
		)
	)
	(footprint ""
		(layer "F.Cu")
		(at 169.59199 -212.420454 180)
		(property "Reference" "C140"
			(at 0 0 180)
			(layer "F.SilkS")
			(hide yes)
			(effects
				(font
					(size 1.27 1.27)
				)
			)
		)
		(property "Value" "SCD22U10V2KX-1GP"
			(at 1.1811 -2.7051 180)
			(unlocked yes)
			(layer "F.Fab")
			(hide yes)
			(effects
				(font
					(size 1.016 1.016)
					(thickness 0.1524)
				)
			)
		)
		(property "Device Type" "C402H22"
			(at 1.1811 -4.2291 180)
			(unlocked yes)
			(layer "F.Fab")
			(hide yes)
			(effects
				(font
					(size 1.016 1.016)
					(thickness 0.1524)
				)
			)
		)
		(duplicate_pad_numbers_are_jumpers no)
		(fp_rect
			(start -0.4318 0.9525)
			(end 0.4318 -0.9525)
			(stroke
				(width 0)
				(type default)
			)
			(fill no)
			(layer "F.CrtYd")
		)
		(fp_rect
			(start -0.4318 0.9525)
			(end 0.4318 -0.9525)
			(stroke
				(width 0)
				(type default)
			)
			(fill no)
			(layer "F.Fab")
		)
		(pad "1" smd custom
			(at 0 -0.4445 180)
			(size 0.1524 0.1524)
			(layers "F.Cu" "F.Mask" "F.Paste")
			(net "PCIE_TX_CAP_P50")
			(options
				(clearance outline)
				(anchor circle)
			)
			(primitives
				(gr_poly
					(pts
						(arc
							(start 0.3048 -0.2032)
							(mid 0.275042 -0.275042)
							(end 0.2032 -0.3048)
						)
						(arc
							(start -0.2032 -0.3048)
							(mid -0.275042 -0.275042)
							(end -0.3048 -0.2032)
						)
						(arc
							(start -0.3048 0.2032)
							(mid -0.275042 0.275042)
							(end -0.2032 0.3048)
						)
						(arc
							(start 0.2032 0.3048)
							(mid 0.275042 0.275042)
							(end 0.3048 0.2032)
						)
					)
					(width 0)
					(fill yes)
				)
			)
		)
		(pad "2" smd custom
			(at 0 0.4445 180)
			(size 0.1524 0.1524)
			(layers "F.Cu" "F.Mask" "F.Paste")
			(net "PCIE_TX_P50")
			(options
				(clearance outline)
				(anchor circle)
			)
			(primitives
				(gr_poly
					(pts
						(arc
							(start 0.3048 -0.2032)
							(mid 0.275042 -0.275042)
							(end 0.2032 -0.3048)
						)
						(arc
							(start -0.2032 -0.3048)
							(mid -0.275042 -0.275042)
							(end -0.3048 -0.2032)
						)
						(arc
							(start -0.3048 0.2032)
							(mid -0.275042 0.275042)
							(end -0.2032 0.3048)
						)
						(arc
							(start 0.2032 0.3048)
							(mid 0.275042 0.275042)
							(end 0.3048 0.2032)
						)
					)
					(width 0)
					(fill yes)
				)
			)
		)
	)
	(footprint ""
		(layer "F.Cu")
		(at 19.685 -182.7022 90)
		(property "Reference" "C8099"
			(at 0 0 90)
			(layer "F.SilkS")
			(hide yes)
			(effects
				(font
					(size 1.27 1.27)
				)
			)
		)
		(property "Value" "SC1KP50V2KX-1GP"
			(at 1.1811 -2.7051 90)
			(unlocked yes)
			(layer "F.Fab")
			(hide yes)
			(effects
				(font
					(size 1.016 1.016)
					(thickness 0.1524)
				)
			)
		)
		(property "Device Type" "C402H22"
			(at 1.1811 -4.2291 90)
			(unlocked yes)
			(layer "F.Fab")
			(hide yes)
			(effects
				(font
					(size 1.016 1.016)
					(thickness 0.1524)
				)
			)
		)
		(duplicate_pad_numbers_are_jumpers no)
		(fp_rect
			(start -0.4318 0.9525)
			(end 0.4318 -0.9525)
			(stroke
				(width 0)
				(type default)
			)
			(fill no)
			(layer "F.CrtYd")
		)
		(fp_rect
			(start -0.4318 0.9525)
			(end 0.4318 -0.9525)
			(stroke
				(width 0)
				(type default)
			)
			(fill no)
			(layer "F.Fab")
		)
		(pad "1" smd custom
			(at 0 -0.4445 90)
			(size 0.1524 0.1524)
			(layers "F.Cu" "F.Mask" "F.Paste")
			(net "MB0_TEMP")
			(options
				(clearance outline)
				(anchor circle)
			)
			(primitives
				(gr_poly
					(pts
						(arc
							(start 0.3048 -0.2032)
							(mid 0.275042 -0.275042)
							(end 0.2032 -0.3048)
						)
						(arc
							(start -0.2032 -0.3048)
							(mid -0.275042 -0.275042)
							(end -0.3048 -0.2032)
						)
						(arc
							(start -0.3048 0.2032)
							(mid -0.275042 0.275042)
							(end -0.2032 0.3048)
						)
						(arc
							(start 0.2032 0.3048)
							(mid 0.275042 0.275042)
							(end 0.3048 0.2032)
						)
					)
					(width 0)
					(fill yes)
				)
			)
		)
		(pad "2" smd custom
			(at 0 0.4445 90)
			(size 0.1524 0.1524)
			(layers "F.Cu" "F.Mask" "F.Paste")
			(net "GND")
			(options
				(clearance outline)
				(anchor circle)
			)
			(primitives
				(gr_poly
					(pts
						(arc
							(start 0.3048 -0.2032)
							(mid 0.275042 -0.275042)
							(end 0.2032 -0.3048)
						)
						(arc
							(start -0.2032 -0.3048)
							(mid -0.275042 -0.275042)
							(end -0.3048 -0.2032)
						)
						(arc
							(start -0.3048 0.2032)
							(mid -0.275042 0.275042)
							(end -0.2032 0.3048)
						)
						(arc
							(start 0.2032 0.3048)
							(mid 0.275042 0.275042)
							(end 0.3048 0.2032)
						)
					)
					(width 0)
					(fill yes)
				)
			)
		)
	)
	(footprint ""
		(layer "F.Cu")
		(at 46.765464 -116.91874)
		(property "Reference" "R562"
			(at 0 0 0)
			(layer "F.SilkS")
			(hide yes)
			(effects
				(font
					(size 1.27 1.27)
				)
			)
		)
		(property "Value" "0R2J-2-GP"
			(at 0.064008 -3.993896 0)
			(unlocked yes)
			(layer "F.Fab")
			(hide yes)
			(effects
				(font
					(size 1.016 1.016)
					(thickness 0.1524)
				)
			)
		)
		(property "Device Type" "R402H16"
			(at 0.064008 -5.517896 0)
			(unlocked yes)
			(layer "F.Fab")
			(hide yes)
			(effects
				(font
					(size 1.016 1.016)
					(thickness 0.1524)
				)
			)
		)
		(duplicate_pad_numbers_are_jumpers no)
		(fp_line
			(start -0.508 -0.9398)
			(end -0.508 0.9398)
			(stroke
				(width 0.1524)
				(type default)
			)
			(layer "F.SilkS")
		)
		(fp_line
			(start 0.508 -0.9398)
			(end -0.508 -0.9398)
			(stroke
				(width 0.1524)
				(type default)
			)
			(layer "F.SilkS")
		)
		(fp_rect
			(start -0.508 0.9398)
			(end 0.508 -0.9398)
			(stroke
				(width 0)
				(type default)
			)
			(fill no)
			(layer "F.CrtYd")
		)
		(fp_rect
			(start -0.508 0.9398)
			(end 0.508 -0.9398)
			(stroke
				(width 0)
				(type default)
			)
			(fill no)
			(layer "F.Fab")
		)
		(pad "1" smd custom
			(at 0 -0.4445)
			(size 0.1397 0.1397)
			(layers "F.Cu" "F.Mask" "F.Paste")
			(net "BMC_JTAG_L_EN_R")
			(options
				(clearance outline)
				(anchor circle)
			)
			(primitives
				(gr_poly
					(pts
						(arc
							(start -0.1778 -0.2794)
							(mid -0.249642 -0.249642)
							(end -0.2794 -0.1778)
						)
						(arc
							(start -0.2794 0.1778)
							(mid -0.249642 0.249642)
							(end -0.1778 0.2794)
						)
						(arc
							(start 0.1778 0.2794)
							(mid 0.249642 0.249642)
							(end 0.2794 0.1778)
						)
						(arc
							(start 0.2794 -0.1778)
							(mid 0.249642 -0.249642)
							(end 0.1778 -0.2794)
						)
					)
					(width 0)
					(fill yes)
				)
			)
		)
		(pad "2" smd custom
			(at 0 0.4445)
			(size 0.1397 0.1397)
			(layers "F.Cu" "F.Mask" "F.Paste")
			(net "BMC_JTAG_L_EN")
			(options
				(clearance outline)
				(anchor circle)
			)
			(primitives
				(gr_poly
					(pts
						(arc
							(start -0.1778 -0.2794)
							(mid -0.249642 -0.249642)
							(end -0.2794 -0.1778)
						)
						(arc
							(start -0.2794 0.1778)
							(mid -0.249642 0.249642)
							(end -0.1778 0.2794)
						)
						(arc
							(start 0.1778 0.2794)
							(mid 0.249642 0.249642)
							(end 0.2794 0.1778)
						)
						(arc
							(start 0.2794 -0.1778)
							(mid 0.249642 -0.249642)
							(end 0.1778 -0.2794)
						)
					)
					(width 0)
					(fill yes)
				)
			)
		)
	)
	(footprint ""
		(layer "F.Cu")
		(at 53.213 -130.048)
		(property "Reference" "C191"
			(at 0 0 0)
			(layer "F.SilkS")
			(hide yes)
			(effects
				(font
					(size 1.27 1.27)
				)
			)
		)
		(property "Value" "SCD1U16V2KX-3GP"
			(at 1.1811 -2.7051 0)
			(unlocked yes)
			(layer "F.Fab")
			(hide yes)
			(effects
				(font
					(size 1.016 1.016)
					(thickness 0.1524)
				)
			)
		)
		(property "Device Type" "C402H22"
			(at 1.1811 -4.2291 0)
			(unlocked yes)
			(layer "F.Fab")
			(hide yes)
			(effects
				(font
					(size 1.016 1.016)
					(thickness 0.1524)
				)
			)
		)
		(duplicate_pad_numbers_are_jumpers no)
		(fp_rect
			(start -0.4318 0.9525)
			(end 0.4318 -0.9525)
			(stroke
				(width 0)
				(type default)
			)
			(fill no)
			(layer "F.CrtYd")
		)
		(fp_rect
			(start -0.4318 0.9525)
			(end 0.4318 -0.9525)
			(stroke
				(width 0)
				(type default)
			)
			(fill no)
			(layer "F.Fab")
		)
		(pad "1" smd custom
			(at 0 -0.4445)
			(size 0.1524 0.1524)
			(layers "F.Cu" "F.Mask" "F.Paste")
			(net "ADCVREFFN")
			(options
				(clearance outline)
				(anchor circle)
			)
			(primitives
				(gr_poly
					(pts
						(arc
							(start 0.3048 -0.2032)
							(mid 0.275042 -0.275042)
							(end 0.2032 -0.3048)
						)
						(arc
							(start -0.2032 -0.3048)
							(mid -0.275042 -0.275042)
							(end -0.3048 -0.2032)
						)
						(arc
							(start -0.3048 0.2032)
							(mid -0.275042 0.275042)
							(end -0.2032 0.3048)
						)
						(arc
							(start 0.2032 0.3048)
							(mid 0.275042 0.275042)
							(end 0.3048 0.2032)
						)
					)
					(width 0)
					(fill yes)
				)
			)
		)
		(pad "2" smd custom
			(at 0 0.4445)
			(size 0.1524 0.1524)
			(layers "F.Cu" "F.Mask" "F.Paste")
			(net "ADCVREFFP")
			(options
				(clearance outline)
				(anchor circle)
			)
			(primitives
				(gr_poly
					(pts
						(arc
							(start 0.3048 -0.2032)
							(mid 0.275042 -0.275042)
							(end 0.2032 -0.3048)
						)
						(arc
							(start -0.2032 -0.3048)
							(mid -0.275042 -0.275042)
							(end -0.3048 -0.2032)
						)
						(arc
							(start -0.3048 0.2032)
							(mid -0.275042 0.275042)
							(end -0.2032 0.3048)
						)
						(arc
							(start 0.2032 0.3048)
							(mid 0.275042 0.275042)
							(end 0.3048 0.2032)
						)
					)
					(width 0)
					(fill yes)
				)
			)
		)
	)
)
